(kicad_pcb
	(version 20260206)
	(generator "pcbnew")
	(generator_version "10.0")
	(general
		(thickness 1.6)
		(legacy_teardrops no)
	)
	(paper "A4")
	(title_block
		(title "dpb — 14545-sa.0730WZS0815.brd")
		(comment 1 "Honey Badger (Wiwynn) / footprints 578-583 of 1066")
	)
	(layers
		(0 "F.Cu" signal "TOP")
		(4 "In1.Cu" signal "L2GND")
		(6 "In2.Cu" signal "L3")
		(8 "In3.Cu" signal "L4VCC")
		(10 "In4.Cu" signal "L5VCC")
		(12 "In5.Cu" signal "L6")
		(14 "In6.Cu" signal "L7GND")
		(2 "B.Cu" signal "BOTTOM")
		(9 "F.Adhes" user "F.Adhesive")
		(11 "B.Adhes" user "B.Adhesive")
		(13 "F.Paste" user "Package Geometry/Pastemask Top")
		(15 "B.Paste" user "Package Geometry/Pastemask Bottom")
		(5 "F.SilkS" user "Ref Des/Silkscreen Top")
		(7 "B.SilkS" user "Ref Des/Silkscreen Bottom")
		(1 "F.Mask" user "Board Geometry/Soldermask Top")
		(3 "B.Mask" user "Board Geometry/Soldermask Bottom")
		(17 "Dwgs.User" user "User.Drawings")
		(19 "Cmts.User" user "User.Comments")
		(21 "Eco1.User" user "User.Eco1")
		(23 "Eco2.User" user "User.Eco2")
		(25 "Edge.Cuts" user "Board Geometry/Outline")
		(27 "Margin" user)
		(31 "F.CrtYd" user "Package Geometry/Place Bound Top")
		(29 "B.CrtYd" user "Package Geometry/Place Bound Bottom")
		(35 "F.Fab" user "Ref Des/Assembly Top")
		(33 "B.Fab" user "Ref Des/Assembly Bottom")
	)
	(footprint ""
		(layer "F.Cu")
		(at 51.562 -416.433)
		(property "Reference" "R573"
			(at 0 0 0)
			(layer "F.SilkS")
			(hide yes)
			(effects
				(font
					(size 1.27 1.27)
				)
			)
		)
		(property "Value" "300KR2F-GP"
			(at 0.064008 -3.993896 0)
			(unlocked yes)
			(layer "F.Fab")
			(hide yes)
			(effects
				(font
					(size 1.016 1.016)
					(thickness 0.1524)
				)
			)
		)
		(property "Device Type" "R402H16"
			(at 0.064008 -5.517896 0)
			(unlocked yes)
			(layer "F.Fab")
			(hide yes)
			(effects
				(font
					(size 1.016 1.016)
					(thickness 0.1524)
				)
			)
		)
		(duplicate_pad_numbers_are_jumpers no)
		(fp_line
			(start -0.508 -0.9398)
			(end -0.508 0.9398)
			(stroke
				(width 0.1524)
				(type default)
			)
			(layer "F.SilkS")
		)
		(fp_line
			(start 0.508 -0.9398)
			(end -0.508 -0.9398)
			(stroke
				(width 0.1524)
				(type default)
			)
			(layer "F.SilkS")
		)
		(fp_rect
			(start -0.508 0.9398)
			(end 0.508 -0.9398)
			(stroke
				(width 0)
				(type default)
			)
			(fill no)
			(layer "F.CrtYd")
		)
		(fp_rect
			(start -0.508 0.9398)
			(end 0.508 -0.9398)
			(stroke
				(width 0)
				(type default)
			)
			(fill no)
			(layer "F.Fab")
		)
		(pad "1" smd custom
			(at 0 -0.4445)
			(size 0.1397 0.1397)
			(layers "F.Cu" "F.Mask" "F.Paste")
			(net "SW_HDD10_N")
			(options
				(clearance outline)
				(anchor circle)
			)
			(primitives
				(gr_poly
					(pts
						(arc
							(start -0.1778 -0.2794)
							(mid -0.249642 -0.249642)
							(end -0.2794 -0.1778)
						)
						(arc
							(start -0.2794 0.1778)
							(mid -0.249642 0.249642)
							(end -0.1778 0.2794)
						)
						(arc
							(start 0.1778 0.2794)
							(mid 0.249642 0.249642)
							(end 0.2794 0.1778)
						)
						(arc
							(start 0.2794 -0.1778)
							(mid 0.249642 -0.249642)
							(end 0.1778 -0.2794)
						)
					)
					(width 0)
					(fill yes)
				)
			)
		)
		(pad "2" smd custom
			(at 0 0.4445)
			(size 0.1397 0.1397)
			(layers "F.Cu" "F.Mask" "F.Paste")
			(net "P12V")
			(options
				(clearance outline)
				(anchor circle)
			)
			(primitives
				(gr_poly
					(pts
						(arc
							(start -0.1778 -0.2794)
							(mid -0.249642 -0.249642)
							(end -0.2794 -0.1778)
						)
						(arc
							(start -0.2794 0.1778)
							(mid -0.249642 0.249642)
							(end -0.1778 0.2794)
						)
						(arc
							(start 0.1778 0.2794)
							(mid 0.249642 0.249642)
							(end 0.2794 0.1778)
						)
						(arc
							(start 0.2794 -0.1778)
							(mid 0.249642 -0.249642)
							(end 0.1778 -0.2794)
						)
					)
					(width 0)
					(fill yes)
				)
			)
		)
	)
	(footprint ""
		(layer "F.Cu")
		(at 199.850756 -498.402102 -90)
		(property "Reference" "U2"
			(at 0 0 270)
			(layer "F.SilkS")
			(hide yes)
			(effects
				(font
					(size 1.27 1.27)
				)
			)
		)
		(property "Value" "P2003EVG-GP"
			(at 0 -11.1252 270)
			(unlocked yes)
			(layer "F.Fab")
			(hide yes)
			(effects
				(font
					(size 1.016 1.016)
					(thickness 0.1524)
				)
			)
		)
		(property "Device Type" "SOIC8H79"
			(at 0 -12.6492 270)
			(unlocked yes)
			(layer "F.Fab")
			(hide yes)
			(effects
				(font
					(size 1.016 1.016)
					(thickness 0.1524)
				)
			)
		)
		(duplicate_pad_numbers_are_jumpers no)
		(fp_line
			(start -2.6162 3.429)
			(end -2.6162 1.4732)
			(stroke
				(width 0.4064)
				(type default)
			)
			(layer "F.SilkS")
		)
		(fp_line
			(start -2.7432 1.4224)
			(end 2.1336 1.4224)
			(stroke
				(width 0.1524)
				(type default)
			)
			(layer "F.SilkS")
		)
		(fp_line
			(start 2.1336 1.4224)
			(end 2.1336 -1.4224)
			(stroke
				(width 0.1524)
				(type default)
			)
			(layer "F.SilkS")
		)
		(fp_line
			(start -2.2352 0)
			(end -2.7432 0.508)
			(stroke
				(width 0.1524)
				(type default)
			)
			(layer "F.SilkS")
		)
		(fp_line
			(start -2.7432 -0.508)
			(end -2.2352 0)
			(stroke
				(width 0.1524)
				(type default)
			)
			(layer "F.SilkS")
		)
		(fp_line
			(start -2.7432 -1.4224)
			(end -2.7432 1.4224)
			(stroke
				(width 0.1524)
				(type default)
			)
			(layer "F.SilkS")
		)
		(fp_line
			(start 2.1336 -1.4224)
			(end -2.7432 -1.4224)
			(stroke
				(width 0.1524)
				(type default)
			)
			(layer "F.SilkS")
		)
		(fp_poly
			(pts
				(xy 2.2098 -1.4224) (xy 2.2098 1.4224) (xy -2.2225 1.4224) (xy -2.2225 -1.4224)
			)
			(stroke
				(width 0)
				(type default)
			)
			(fill yes)
			(layer "F.SilkS")
		)
		(fp_rect
			(start -2.4511 2.9972)
			(end 2.4511 -2.9972)
			(stroke
				(width 0)
				(type default)
			)
			(fill no)
			(layer "F.CrtYd")
		)
		(fp_poly
			(pts
				(xy -2.8194 3.6322) (xy -2.8194 -3.6322) (xy 2.8194 -3.6322) (xy 2.8194 -2.2987) (xy 2.4511 -2.2987)
				(xy 2.4511 -2.9972) (xy -2.4511 -2.9972) (xy -2.4511 2.9972) (xy 2.4511 2.9972) (xy 2.4511 -2.286)
				(xy 2.8194 -2.286) (xy 2.8194 3.6322)
			)
			(stroke
				(width 0)
				(type default)
			)
			(fill no)
			(layer "F.CrtYd")
		)
		(fp_rect
			(start -2.8194 3.6322)
			(end 2.8194 -3.6322)
			(stroke
				(width 0)
				(type default)
			)
			(fill no)
			(layer "F.Fab")
		)
		(pad "1" smd rect
			(at -1.905 2.54 270)
			(size 0.635 1.651)
			(layers "F.Cu" "F.Mask" "F.Paste")
			(net "P12V")
		)
		(pad "2" smd rect
			(at -0.635 2.54 270)
			(size 0.635 1.651)
			(layers "F.Cu" "F.Mask" "F.Paste")
			(net "P12V")
		)
		(pad "3" smd rect
			(at 0.635 2.54 270)
			(size 0.635 1.651)
			(layers "F.Cu" "F.Mask" "F.Paste")
			(net "P12V")
		)
		(pad "4" smd rect
			(at 1.905 2.54 270)
			(size 0.635 1.651)
			(layers "F.Cu" "F.Mask" "F.Paste")
			(net "SW_HDD0_N")
		)
		(pad "5" smd rect
			(at 1.905 -2.54 270)
			(size 0.635 1.651)
			(layers "F.Cu" "F.Mask" "F.Paste")
			(net "P12V_HDD0")
		)
		(pad "6" smd rect
			(at 0.635 -2.54 270)
			(size 0.635 1.651)
			(layers "F.Cu" "F.Mask" "F.Paste")
			(net "P12V_HDD0")
		)
		(pad "7" smd rect
			(at -0.635 -2.54 270)
			(size 0.635 1.651)
			(layers "F.Cu" "F.Mask" "F.Paste")
			(net "P12V_HDD0")
		)
		(pad "8" smd rect
			(at -1.905 -2.54 270)
			(size 0.635 1.651)
			(layers "F.Cu" "F.Mask" "F.Paste")
			(net "P12V_HDD0")
		)
	)
	(footprint ""
		(layer "F.Cu")
		(at 33.043368 -468.948516 -90)
		(property "Reference" "C182"
			(at 0 0 270)
			(layer "F.SilkS")
			(hide yes)
			(effects
				(font
					(size 1.27 1.27)
				)
			)
		)
		(property "Value" "SCD01U50V2KX-1GP"
			(at 1.1811 -2.7051 270)
			(unlocked yes)
			(layer "F.Fab")
			(hide yes)
			(effects
				(font
					(size 1.016 1.016)
					(thickness 0.1524)
				)
			)
		)
		(property "Device Type" "C402H22"
			(at 1.1811 -4.2291 270)
			(unlocked yes)
			(layer "F.Fab")
			(hide yes)
			(effects
				(font
					(size 1.016 1.016)
					(thickness 0.1524)
				)
			)
		)
		(duplicate_pad_numbers_are_jumpers no)
		(fp_rect
			(start -0.4318 0.9525)
			(end 0.4318 -0.9525)
			(stroke
				(width 0)
				(type default)
			)
			(fill no)
			(layer "F.CrtYd")
		)
		(fp_rect
			(start -0.4318 0.9525)
			(end 0.4318 -0.9525)
			(stroke
				(width 0)
				(type default)
			)
			(fill no)
			(layer "F.Fab")
		)
		(pad "1" smd custom
			(at 0 -0.4445 270)
			(size 0.1524 0.1524)
			(layers "F.Cu" "F.Mask" "F.Paste")
			(net "SAS2X28_DRIVE_RX_N_A5")
			(options
				(clearance outline)
				(anchor circle)
			)
			(primitives
				(gr_poly
					(pts
						(arc
							(start 0.3048 -0.2032)
							(mid 0.275042 -0.275042)
							(end 0.2032 -0.3048)
						)
						(arc
							(start -0.2032 -0.3048)
							(mid -0.275042 -0.275042)
							(end -0.3048 -0.2032)
						)
						(arc
							(start -0.3048 0.2032)
							(mid -0.275042 0.275042)
							(end -0.2032 0.3048)
						)
						(arc
							(start 0.2032 0.3048)
							(mid 0.275042 0.275042)
							(end 0.3048 0.2032)
						)
					)
					(width 0)
					(fill yes)
				)
			)
		)
		(pad "2" smd custom
			(at 0 0.4445 270)
			(size 0.1524 0.1524)
			(layers "F.Cu" "F.Mask" "F.Paste")
			(net "SAS2X28_A_HDD5_RX_-")
			(options
				(clearance outline)
				(anchor circle)
			)
			(primitives
				(gr_poly
					(pts
						(arc
							(start 0.3048 -0.2032)
							(mid 0.275042 -0.275042)
							(end 0.2032 -0.3048)
						)
						(arc
							(start -0.2032 -0.3048)
							(mid -0.275042 -0.275042)
							(end -0.3048 -0.2032)
						)
						(arc
							(start -0.3048 0.2032)
							(mid -0.275042 0.275042)
							(end -0.2032 0.3048)
						)
						(arc
							(start 0.2032 0.3048)
							(mid 0.275042 0.275042)
							(end 0.3048 0.2032)
						)
					)
					(width 0)
					(fill yes)
				)
			)
		)
	)
	(footprint ""
		(layer "F.Cu")
		(at 40.055546 -133.3119 -90)
		(property "Reference" "R323"
			(at 0 0 270)
			(layer "F.SilkS")
			(hide yes)
			(effects
				(font
					(size 1.27 1.27)
				)
			)
		)
		(property "Value" "4K7R2J-2-GP"
			(at 0.064008 -3.993896 270)
			(unlocked yes)
			(layer "F.Fab")
			(hide yes)
			(effects
				(font
					(size 1.016 1.016)
					(thickness 0.1524)
				)
			)
		)
		(property "Device Type" "R402H16"
			(at 0.064008 -5.517896 270)
			(unlocked yes)
			(layer "F.Fab")
			(hide yes)
			(effects
				(font
					(size 1.016 1.016)
					(thickness 0.1524)
				)
			)
		)
		(duplicate_pad_numbers_are_jumpers no)
		(fp_line
			(start -0.508 -0.9398)
			(end -0.508 0.9398)
			(stroke
				(width 0.1524)
				(type default)
			)
			(layer "F.SilkS")
		)
		(fp_line
			(start 0.508 -0.9398)
			(end -0.508 -0.9398)
			(stroke
				(width 0.1524)
				(type default)
			)
			(layer "F.SilkS")
		)
		(fp_rect
			(start -0.508 0.9398)
			(end 0.508 -0.9398)
			(stroke
				(width 0)
				(type default)
			)
			(fill no)
			(layer "F.CrtYd")
		)
		(fp_rect
			(start -0.508 0.9398)
			(end 0.508 -0.9398)
			(stroke
				(width 0)
				(type default)
			)
			(fill no)
			(layer "F.Fab")
		)
		(pad "1" smd custom
			(at 0 -0.4445 270)
			(size 0.1397 0.1397)
			(layers "F.Cu" "F.Mask" "F.Paste")
			(net "I2C_B_TMP2_A2")
			(options
				(clearance outline)
				(anchor circle)
			)
			(primitives
				(gr_poly
					(pts
						(arc
							(start -0.1778 -0.2794)
							(mid -0.249642 -0.249642)
							(end -0.2794 -0.1778)
						)
						(arc
							(start -0.2794 0.1778)
							(mid -0.249642 0.249642)
							(end -0.1778 0.2794)
						)
						(arc
							(start 0.1778 0.2794)
							(mid 0.249642 0.249642)
							(end 0.2794 0.1778)
						)
						(arc
							(start 0.2794 -0.1778)
							(mid 0.249642 -0.249642)
							(end 0.1778 -0.2794)
						)
					)
					(width 0)
					(fill yes)
				)
			)
		)
		(pad "2" smd custom
			(at 0 0.4445 270)
			(size 0.1397 0.1397)
			(layers "F.Cu" "F.Mask" "F.Paste")
			(net "GND")
			(options
				(clearance outline)
				(anchor circle)
			)
			(primitives
				(gr_poly
					(pts
						(arc
							(start -0.1778 -0.2794)
							(mid -0.249642 -0.249642)
							(end -0.2794 -0.1778)
						)
						(arc
							(start -0.2794 0.1778)
							(mid -0.249642 0.249642)
							(end -0.1778 0.2794)
						)
						(arc
							(start 0.1778 0.2794)
							(mid 0.249642 0.249642)
							(end 0.2794 0.1778)
						)
						(arc
							(start 0.2794 -0.1778)
							(mid 0.249642 -0.249642)
							(end 0.1778 -0.2794)
						)
					)
					(width 0)
					(fill yes)
				)
			)
		)
	)
	(footprint ""
		(layer "F.Cu")
		(at 27.304746 -437.035702 90)
		(property "Reference" "R461"
			(at 0 0 90)
			(layer "F.SilkS")
			(hide yes)
			(effects
				(font
					(size 1.27 1.27)
				)
			)
		)
		(property "Value" "4K7R2J-2-GP"
			(at 0.064008 -3.993896 90)
			(unlocked yes)
			(layer "F.Fab")
			(hide yes)
			(effects
				(font
					(size 1.016 1.016)
					(thickness 0.1524)
				)
			)
		)
		(property "Device Type" "R402H16"
			(at 0.064008 -5.517896 90)
			(unlocked yes)
			(layer "F.Fab")
			(hide yes)
			(effects
				(font
					(size 1.016 1.016)
					(thickness 0.1524)
				)
			)
		)
		(duplicate_pad_numbers_are_jumpers no)
		(fp_line
			(start 0.508 -0.9398)
			(end -0.508 -0.9398)
			(stroke
				(width 0.1524)
				(type default)
			)
			(layer "F.SilkS")
		)
		(fp_line
			(start -0.508 -0.9398)
			(end -0.508 0.9398)
			(stroke
				(width 0.1524)
				(type default)
			)
			(layer "F.SilkS")
		)
		(fp_rect
			(start -0.508 0.9398)
			(end 0.508 -0.9398)
			(stroke
				(width 0)
				(type default)
			)
			(fill no)
			(layer "F.CrtYd")
		)
		(fp_rect
			(start -0.508 0.9398)
			(end 0.508 -0.9398)
			(stroke
				(width 0)
				(type default)
			)
			(fill no)
			(layer "F.Fab")
		)
		(pad "1" smd custom
			(at 0 -0.4445 90)
			(size 0.1397 0.1397)
			(layers "F.Cu" "F.Mask" "F.Paste")
			(net "P3V3")
			(options
				(clearance outline)
				(anchor circle)
			)
			(primitives
				(gr_poly
					(pts
						(arc
							(start -0.1778 -0.2794)
							(mid -0.249642 -0.249642)
							(end -0.2794 -0.1778)
						)
						(arc
							(start -0.2794 0.1778)
							(mid -0.249642 0.249642)
							(end -0.1778 0.2794)
						)
						(arc
							(start 0.1778 0.2794)
							(mid 0.249642 0.249642)
							(end 0.2794 0.1778)
						)
						(arc
							(start 0.2794 -0.1778)
							(mid 0.249642 -0.249642)
							(end 0.1778 -0.2794)
						)
					)
					(width 0)
					(fill yes)
				)
			)
		)
		(pad "2" smd custom
			(at 0 0.4445 90)
			(size 0.1397 0.1397)
			(layers "F.Cu" "F.Mask" "F.Paste")
			(net "SAS2X28_B_HDD10_FLT")
			(options
				(clearance outline)
				(anchor circle)
			)
			(primitives
				(gr_poly
					(pts
						(arc
							(start -0.1778 -0.2794)
							(mid -0.249642 -0.249642)
							(end -0.2794 -0.1778)
						)
						(arc
							(start -0.2794 0.1778)
							(mid -0.249642 0.249642)
							(end -0.1778 0.2794)
						)
						(arc
							(start 0.1778 0.2794)
							(mid 0.249642 0.249642)
							(end 0.2794 0.1778)
						)
						(arc
							(start 0.2794 -0.1778)
							(mid 0.249642 -0.249642)
							(end 0.1778 -0.2794)
						)
					)
					(width 0)
					(fill yes)
				)
			)
		)
	)
	(footprint ""
		(layer "F.Cu")
		(at 214.778082 -278.559768 -90)
		(property "Reference" "R134"
			(at 0 0 270)
			(layer "F.SilkS")
			(hide yes)
			(effects
				(font
					(size 1.27 1.27)
				)
			)
		)
		(property "Value" "2R2010J-1-GP"
			(at 0.254 -8.0772 270)
			(unlocked yes)
			(layer "F.Fab")
			(hide yes)
			(effects
				(font
					(size 1.016 1.016)
					(thickness 0.1524)
				)
			)
		)
		(property "Device Type" "R2010H28"
			(at 0.254 -9.6774 270)
			(unlocked yes)
			(layer "F.Fab")
			(hide yes)
			(effects
				(font
					(size 1.016 1.016)
					(thickness 0.1524)
				)
			)
		)
		(duplicate_pad_numbers_are_jumpers no)
		(fp_line
			(start -1.651 3.302)
			(end 1.651 3.302)
			(stroke
				(width 0.1524)
				(type default)
			)
			(layer "F.SilkS")
		)
		(fp_line
			(start 1.651 3.302)
			(end 1.651 -3.302)
			(stroke
				(width 0.1524)
				(type default)
			)
			(layer "F.SilkS")
		)
		(fp_line
			(start -1.651 -3.302)
			(end -1.651 3.302)
			(stroke
				(width 0.1524)
				(type default)
			)
			(layer "F.SilkS")
		)
		(fp_line
			(start 1.651 -3.302)
			(end -1.651 -3.302)
			(stroke
				(width 0.1524)
				(type default)
			)
			(layer "F.SilkS")
		)
		(fp_rect
			(start -1.7272 -3.3782)
			(end 1.7272 3.3782)
			(stroke
				(width 0)
				(type default)
			)
			(fill no)
			(layer "F.CrtYd")
		)
		(fp_poly
			(pts
				(xy 1.7272 3.3782) (xy 1.7272 -3.3782) (xy -1.7272 -3.3782) (xy -1.7272 3.3782)
			)
			(stroke
				(width 0)
				(type default)
			)
			(fill no)
			(layer "F.Fab")
		)
		(pad "1" smd rect
			(at 0 -2.3495 270)
			(size 2.794 1.143)
			(layers "F.Cu" "F.Mask" "F.Paste")
			(net "5V_PRE_2")
		)
		(pad "2" smd rect
			(at 0 2.3495 270)
			(size 2.794 1.143)
			(layers "F.Cu" "F.Mask" "F.Paste")
			(net "P5V_HDD2")
		)
	)
)
